#ISCELL
  mstr_misc dns *
  *
#ISCELL
  pure_quanta quanta_title_block_c *
  *
#ISCELL
  standard offpage *
  page144_i1
#ISCELL
  pure_quanta_power universal_gnd *
  page144_i10
#ISCELL
  standard offpage *
  page144_i11
#ISCELL
  standard offpage *
  page144_i12
#ISCELL
  standard offpage *
  page144_i13
#ISCELL
  standard offpage *
  page144_i14
#CELL
  pure_quanta q_res *
  page144_i15
#ISCELL
  pure_quanta_power universal_power *
  page144_i16
#CELL
  pure_quanta q_res *
  page144_i17
#CELL
  pure_quanta q_res *
  page144_i19
#ISCELL
  standard offpage *
  page144_i2
#ISCELL
  standard offpage *
  page144_i20
#ISCELL
  standard offpage *
  page144_i21
#ISCELL
  standard offpage *
  page144_i22
#ISCELL
  standard offpage *
  page144_i23
#ISCELL
  standard offpage *
  page144_i24
#ISCELL
  standard offpage *
  page144_i25
#ISCELL
  standard offpage *
  page144_i26
#ISCELL
  standard offpage *
  page144_i27
#ISCELL
  standard offpage *
  page144_i28
#ISCELL
  standard offpage *
  page144_i29
#ISCELL
  standard offpage *
  page144_i3
#CELL
  pure_quanta q_res *
  page144_i30
#ISCELL
  pure_quanta_power universal_power *
  page144_i31
#ISCELL
  pure_quanta_power universal_gnd *
  page144_i32
#CELL
  pure_quanta q_res *
  page144_i33
#CELL
  pure_quanta q_res *
  page144_i34
#ISCELL
  standard offpage *
  page144_i35
#ISCELL
  pure_quanta_power universal_gnd *
  page144_i36
#ISCELL
  pure_quanta_power universal_gnd *
  page144_i37
#CELL
  pure_quanta sn74lvc1g07dbvr *
  page144_i38
#CELL
  pure_quanta q_cap *
  page144_i39
#ISCELL
  pure_quanta_power universal_gnd *
  page144_i4
#ISCELL
  pure_quanta_power universal_power *
  page144_i40
#ISCELL
  standard offpage *
  page144_i41
#ISCELL
  standard offpage *
  page144_i42
#ISCELL
  standard offpage *
  page144_i43
#CELL
  pure_quanta q_res *
  page144_i44
#ISCELL
  pure_quanta_power universal_power *
  page144_i45
#ISCELL
  pure_quanta_power universal_gnd *
  page144_i46
#CELL
  pure_quanta q_res *
  page144_i47
#ISCELL
  pure_quanta_power universal_power *
  page144_i48
#ISCELL
  standard offpage *
  page144_i49
#ISCELL
  pure_quanta_power universal_gnd *
  page144_i5
#CELL
  pure_quanta q_res *
  page144_i50
#ISCELL
  pure_quanta_power universal_power *
  page144_i51
#CELL
  pure_quanta q_res *
  page144_i52
#ISCELL
  pure_quanta_power universal_gnd *
  page144_i53
#CELL
  pure_quanta q_res *
  page144_i54
#ISCELL
  pure_quanta_power universal_power *
  page144_i55
#ISCELL
  standard offpage *
  page144_i56
#ISCELL
  standard offpage *
  page144_i57
#ISCELL
  standard offpage *
  page144_i58
#ISCELL
  standard offpage *
  page144_i59
#CELL
  pure_quanta q_res *
  page144_i6
#ISCELL
  pure_quanta_power universal_gnd *
  page144_i60
#CELL
  pure_quanta q_res *
  page144_i61
#CELL
  pure_quanta q_res *
  page144_i62
#ISCELL
  pure_quanta_power universal_power *
  page144_i63
#ISCELL
  standard offpage *
  page144_i64
#ISCELL
  standard offpage *
  page144_i65
#ISCELL
  pure_quanta_power universal_gnd *
  page144_i66
#ISCELL
  standard offpage *
  page144_i67
#ISCELL
  standard offpage *
  page144_i68
#CELL
  pure_quanta q_res *
  page144_i69
#ISCELL
  standard offpage *
  page144_i7
#CELL
  pure_quanta q_res *
  page144_i70
#ISCELL
  pure_quanta_power universal_power *
  page144_i71
#CELL
  pure_quanta q_res *
  page144_i72
#ISCELL
  pure_quanta_power universal_power *
  page144_i73
#CELL
  pure_quanta q_res *
  page144_i74
#ISCELL
  standard offpage *
  page144_i75
#ISCELL
  pure_quanta_power universal_power *
  page144_i76
#CELL
  pure_quanta q_res *
  page144_i77
#ISCELL
  pure_quanta_power universal_power *
  page144_i78
#ISCELL
  pure_quanta_power universal_gnd *
  page144_i79
#ISCELL
  standard offpage *
  page144_i8
#ISCELL
  pure_quanta_power universal_power *
  page144_i80
#CELL
  pure_quanta q_res *
  page144_i81
#ISCELL
  pure_quanta_power universal_power *
  page144_i82
#CELL
  pure_quanta q_res *
  page144_i83
#CELL
  pure_quanta q_res *
  page144_i84
#CELL
  pure_quanta q_res *
  page144_i85
#ISCELL
  pure_quanta_power universal_power *
  page144_i86
#ISCELL
  pure_quanta_power universal_power *
  page144_i87
#CELL
  pure_quanta q_res *
  page144_i89
#ISCELL
  standard offpage *
  page144_i9
#CELL
  pure_quanta sw20s_dhnf10fqtr *
  page144_i90
